#ISCELL
  pure_quanta quanta_title_block_c *
  *
#CELL
  pure_quanta socket4677_azif0045p001c01cs *
  page39_i1
#CELL
  pure_quanta socket4677_azif0045p001c01cs *
  page39_i10
#ISCELL
  logical_power universal_gnd *
  page39_i2
#ISCELL
  logical_power universal_gnd *
  page39_i3
#ISCELL
  logical_power universal_gnd *
  page39_i5
#ISCELL
  logical_power universal_gnd *
  page39_i6
#ISCELL
  logical_power universal_gnd *
  page39_i7
#ISCELL
  logical_power universal_gnd *
  page39_i8
#CELL
  pure_quanta socket4677_azif0045p001c01cs *
  page39_i9
